(kicad_pcb
	(version 20260206)
	(generator "pcbnew")
	(generator_version "10.0")
	(general
		(thickness 1.6)
		(legacy_teardrops no)
	)
	(paper "A4")
	(title_block
		(title "ptb — 12523-1.1018WZS1506.brd")
		(comment 1 "Open Vault / Knox (Wiwynn) / footprints 48-54 of 61")
	)
	(layers
		(0 "F.Cu" signal "TOP")
		(4 "In1.Cu" signal "L2GND")
		(6 "In2.Cu" signal "L3VCC")
		(2 "B.Cu" signal "BOTTOM")
		(9 "F.Adhes" user "F.Adhesive")
		(11 "B.Adhes" user "B.Adhesive")
		(13 "F.Paste" user "Package Geometry/Pastemask Top")
		(15 "B.Paste" user "Package Geometry/Pastemask Bottom")
		(5 "F.SilkS" user "Ref Des/Silkscreen Top")
		(7 "B.SilkS" user "Ref Des/Silkscreen Bottom")
		(1 "F.Mask" user "Board Geometry/Soldermask Top")
		(3 "B.Mask" user "Board Geometry/Soldermask Bottom")
		(17 "Dwgs.User" user "User.Drawings")
		(19 "Cmts.User" user "User.Comments")
		(21 "Eco1.User" user "User.Eco1")
		(23 "Eco2.User" user "User.Eco2")
		(25 "Edge.Cuts" user "Board Geometry/Outline")
		(27 "Margin" user)
		(31 "F.CrtYd" user "Package Geometry/Place Bound Top")
		(29 "B.CrtYd" user "Package Geometry/Place Bound Bottom")
		(35 "F.Fab" user "Ref Des/Assembly Top")
		(33 "B.Fab" user "Ref Des/Assembly Bottom")
	)
	(footprint ""
		(layer "F.Cu")
		(at 133.223 -81.788 -90)
		(property "Reference" "R482"
			(at 0 0 270)
			(layer "F.SilkS")
			(hide yes)
			(effects
				(font
					(size 1.27 1.27)
				)
			)
		)
		(property "Value" "0R2J-2-GP"
			(at 0.064008 -3.993896 270)
			(unlocked yes)
			(layer "F.Fab")
			(hide yes)
			(effects
				(font
					(size 1.016 1.016)
					(thickness 0.1524)
				)
			)
		)
		(property "Device Type" "R402H16"
			(at 0.064008 -5.517896 270)
			(unlocked yes)
			(layer "F.Fab")
			(hide yes)
			(effects
				(font
					(size 1.016 1.016)
					(thickness 0.1524)
				)
			)
		)
		(duplicate_pad_numbers_are_jumpers no)
		(fp_line
			(start -0.508 -0.9398)
			(end -0.508 0.9398)
			(stroke
				(width 0.1524)
				(type default)
			)
			(layer "F.SilkS")
		)
		(fp_line
			(start 0.508 -0.9398)
			(end -0.508 -0.9398)
			(stroke
				(width 0.1524)
				(type default)
			)
			(layer "F.SilkS")
		)
		(fp_rect
			(start -0.508 0.9398)
			(end 0.508 -0.9398)
			(stroke
				(width 0)
				(type default)
			)
			(fill no)
			(layer "F.CrtYd")
		)
		(fp_rect
			(start -0.508 0.9398)
			(end 0.508 -0.9398)
			(stroke
				(width 0)
				(type default)
			)
			(fill no)
			(layer "F.Fab")
		)
		(pad "1" smd custom
			(at 0 -0.4445 270)
			(size 0.1397 0.1397)
			(layers "F.Cu" "F.Mask" "F.Paste")
			(net "TRAY PRESENT_OUT#_C")
			(options
				(clearance outline)
				(anchor circle)
			)
			(primitives
				(gr_poly
					(pts
						(arc
							(start -0.1778 -0.2794)
							(mid -0.249642 -0.249642)
							(end -0.2794 -0.1778)
						)
						(arc
							(start -0.2794 0.1778)
							(mid -0.249642 0.249642)
							(end -0.1778 0.2794)
						)
						(arc
							(start 0.1778 0.2794)
							(mid 0.249642 0.249642)
							(end 0.2794 0.1778)
						)
						(arc
							(start 0.2794 -0.1778)
							(mid 0.249642 -0.249642)
							(end 0.1778 -0.2794)
						)
					)
					(width 0)
					(fill yes)
				)
			)
		)
		(pad "2" smd custom
			(at 0 0.4445 270)
			(size 0.1397 0.1397)
			(layers "F.Cu" "F.Mask" "F.Paste")
			(net "TRAY_MOSFET_G")
			(options
				(clearance outline)
				(anchor circle)
			)
			(primitives
				(gr_poly
					(pts
						(arc
							(start -0.1778 -0.2794)
							(mid -0.249642 -0.249642)
							(end -0.2794 -0.1778)
						)
						(arc
							(start -0.2794 0.1778)
							(mid -0.249642 0.249642)
							(end -0.1778 0.2794)
						)
						(arc
							(start 0.1778 0.2794)
							(mid 0.249642 0.249642)
							(end 0.2794 0.1778)
						)
						(arc
							(start 0.2794 -0.1778)
							(mid 0.249642 -0.249642)
							(end 0.1778 -0.2794)
						)
					)
					(width 0)
					(fill yes)
				)
			)
		)
	)
	(footprint ""
		(layer "F.Cu")
		(at 148.082 -19.939)
		(property "Reference" "R391"
			(at 0 0 0)
			(layer "F.SilkS")
			(hide yes)
			(effects
				(font
					(size 1.27 1.27)
				)
			)
		)
		(property "Value" "0R2J-2-GP"
			(at 0.064008 -3.993896 0)
			(unlocked yes)
			(layer "F.Fab")
			(hide yes)
			(effects
				(font
					(size 1.016 1.016)
					(thickness 0.1524)
				)
			)
		)
		(property "Device Type" "R402H16"
			(at 0.064008 -5.517896 0)
			(unlocked yes)
			(layer "F.Fab")
			(hide yes)
			(effects
				(font
					(size 1.016 1.016)
					(thickness 0.1524)
				)
			)
		)
		(duplicate_pad_numbers_are_jumpers no)
		(fp_line
			(start -0.508 -0.9398)
			(end -0.508 0.9398)
			(stroke
				(width 0.1524)
				(type default)
			)
			(layer "F.SilkS")
		)
		(fp_line
			(start 0.508 -0.9398)
			(end -0.508 -0.9398)
			(stroke
				(width 0.1524)
				(type default)
			)
			(layer "F.SilkS")
		)
		(fp_rect
			(start -0.508 0.9398)
			(end 0.508 -0.9398)
			(stroke
				(width 0)
				(type default)
			)
			(fill no)
			(layer "F.CrtYd")
		)
		(fp_rect
			(start -0.508 0.9398)
			(end 0.508 -0.9398)
			(stroke
				(width 0)
				(type default)
			)
			(fill no)
			(layer "F.Fab")
		)
		(pad "1" smd custom
			(at 0 -0.4445)
			(size 0.1397 0.1397)
			(layers "F.Cu" "F.Mask" "F.Paste")
			(net "TPS2490_EN1")
			(options
				(clearance outline)
				(anchor circle)
			)
			(primitives
				(gr_poly
					(pts
						(arc
							(start -0.1778 -0.2794)
							(mid -0.249642 -0.249642)
							(end -0.2794 -0.1778)
						)
						(arc
							(start -0.2794 0.1778)
							(mid -0.249642 0.249642)
							(end -0.1778 0.2794)
						)
						(arc
							(start 0.1778 0.2794)
							(mid 0.249642 0.249642)
							(end 0.2794 0.1778)
						)
						(arc
							(start 0.2794 -0.1778)
							(mid 0.249642 -0.249642)
							(end 0.1778 -0.2794)
						)
					)
					(width 0)
					(fill yes)
				)
			)
		)
		(pad "2" smd custom
			(at 0 0.4445)
			(size 0.1397 0.1397)
			(layers "F.Cu" "F.Mask" "F.Paste")
			(net "TPS2490_EN2")
			(options
				(clearance outline)
				(anchor circle)
			)
			(primitives
				(gr_poly
					(pts
						(arc
							(start -0.1778 -0.2794)
							(mid -0.249642 -0.249642)
							(end -0.2794 -0.1778)
						)
						(arc
							(start -0.2794 0.1778)
							(mid -0.249642 0.249642)
							(end -0.1778 0.2794)
						)
						(arc
							(start 0.1778 0.2794)
							(mid 0.249642 0.249642)
							(end 0.2794 0.1778)
						)
						(arc
							(start 0.2794 -0.1778)
							(mid 0.249642 -0.249642)
							(end 0.1778 -0.2794)
						)
					)
					(width 0)
					(fill yes)
				)
			)
		)
	)
	(footprint ""
		(layer "F.Cu")
		(at 12.27455 -89.9541 180)
		(property "Reference" "R343"
			(at 0 0 180)
			(layer "F.SilkS")
			(hide yes)
			(effects
				(font
					(size 1.27 1.27)
				)
			)
		)
		(property "Value" "10KR2F-2-GP"
			(at 0.064008 -3.993896 180)
			(unlocked yes)
			(layer "F.Fab")
			(hide yes)
			(effects
				(font
					(size 1.016 1.016)
					(thickness 0.1524)
				)
			)
		)
		(property "Device Type" "R402H16"
			(at 0.064008 -5.517896 180)
			(unlocked yes)
			(layer "F.Fab")
			(hide yes)
			(effects
				(font
					(size 1.016 1.016)
					(thickness 0.1524)
				)
			)
		)
		(duplicate_pad_numbers_are_jumpers no)
		(fp_line
			(start 0.508 -0.9398)
			(end -0.508 -0.9398)
			(stroke
				(width 0.1524)
				(type default)
			)
			(layer "F.SilkS")
		)
		(fp_line
			(start -0.508 -0.9398)
			(end -0.508 0.9398)
			(stroke
				(width 0.1524)
				(type default)
			)
			(layer "F.SilkS")
		)
		(fp_rect
			(start -0.508 0.9398)
			(end 0.508 -0.9398)
			(stroke
				(width 0)
				(type default)
			)
			(fill no)
			(layer "F.CrtYd")
		)
		(fp_rect
			(start -0.508 0.9398)
			(end 0.508 -0.9398)
			(stroke
				(width 0)
				(type default)
			)
			(fill no)
			(layer "F.Fab")
		)
		(pad "1" smd custom
			(at 0 -0.4445 180)
			(size 0.1397 0.1397)
			(layers "F.Cu" "F.Mask" "F.Paste")
			(net "P3V3")
			(options
				(clearance outline)
				(anchor circle)
			)
			(primitives
				(gr_poly
					(pts
						(arc
							(start -0.1778 -0.2794)
							(mid -0.249642 -0.249642)
							(end -0.2794 -0.1778)
						)
						(arc
							(start -0.2794 0.1778)
							(mid -0.249642 0.249642)
							(end -0.1778 0.2794)
						)
						(arc
							(start 0.1778 0.2794)
							(mid 0.249642 0.249642)
							(end 0.2794 0.1778)
						)
						(arc
							(start 0.2794 -0.1778)
							(mid 0.249642 -0.249642)
							(end 0.1778 -0.2794)
						)
					)
					(width 0)
					(fill yes)
				)
			)
		)
		(pad "2" smd custom
			(at 0 0.4445 180)
			(size 0.1397 0.1397)
			(layers "F.Cu" "F.Mask" "F.Paste")
			(net "I2C_C_BUF_EN")
			(options
				(clearance outline)
				(anchor circle)
			)
			(primitives
				(gr_poly
					(pts
						(arc
							(start -0.1778 -0.2794)
							(mid -0.249642 -0.249642)
							(end -0.2794 -0.1778)
						)
						(arc
							(start -0.2794 0.1778)
							(mid -0.249642 0.249642)
							(end -0.1778 0.2794)
						)
						(arc
							(start 0.1778 0.2794)
							(mid 0.249642 0.249642)
							(end 0.2794 0.1778)
						)
						(arc
							(start 0.2794 -0.1778)
							(mid 0.249642 -0.249642)
							(end 0.1778 -0.2794)
						)
					)
					(width 0)
					(fill yes)
				)
			)
		)
	)
	(footprint ""
		(layer "F.Cu")
		(at 9.679686 -92.946982)
		(property "Reference" "C358"
			(at 0 0 0)
			(layer "F.SilkS")
			(hide yes)
			(effects
				(font
					(size 1.27 1.27)
				)
			)
		)
		(property "Value" "SC220P50V3JN-GP"
			(at 0 -2.8194 0)
			(unlocked yes)
			(layer "F.Fab")
			(hide yes)
			(effects
				(font
					(size 1.016 1.016)
					(thickness 0.1524)
				)
			)
		)
		(property "Device Type" "C603H36"
			(at 0 -4.3434 0)
			(unlocked yes)
			(layer "F.Fab")
			(hide yes)
			(effects
				(font
					(size 1.016 1.016)
					(thickness 0.1524)
				)
			)
		)
		(duplicate_pad_numbers_are_jumpers no)
		(fp_line
			(start 0.508 0)
			(end -0.508 0)
			(stroke
				(width 0.2032)
				(type default)
			)
			(layer "F.SilkS")
		)
		(fp_rect
			(start -0.5842 1.3335)
			(end 0.5842 -1.3335)
			(stroke
				(width 0)
				(type default)
			)
			(fill no)
			(layer "F.CrtYd")
		)
		(fp_rect
			(start -0.5842 1.3335)
			(end 0.5842 -1.3335)
			(stroke
				(width 0)
				(type default)
			)
			(fill no)
			(layer "F.Fab")
		)
		(pad "1" smd custom
			(at 0 -0.762)
			(size 0.2159 0.2159)
			(layers "F.Cu" "F.Mask" "F.Paste")
			(net "I2C_C_SCL")
			(options
				(clearance outline)
				(anchor circle)
			)
			(primitives
				(gr_poly
					(pts
						(arc
							(start -0.3302 -0.4318)
							(mid -0.402042 -0.402042)
							(end -0.4318 -0.3302)
						)
						(arc
							(start -0.4318 0.3302)
							(mid -0.402042 0.402042)
							(end -0.3302 0.4318)
						)
						(arc
							(start 0.3302 0.4318)
							(mid 0.402042 0.402042)
							(end 0.4318 0.3302)
						)
						(arc
							(start 0.4318 -0.3302)
							(mid 0.402042 -0.402042)
							(end 0.3302 -0.4318)
						)
					)
					(width 0)
					(fill yes)
				)
			)
		)
		(pad "2" smd custom
			(at 0 0.762)
			(size 0.2159 0.2159)
			(layers "F.Cu" "F.Mask" "F.Paste")
			(net "GND")
			(options
				(clearance outline)
				(anchor circle)
			)
			(primitives
				(gr_poly
					(pts
						(arc
							(start -0.3302 -0.4318)
							(mid -0.402042 -0.402042)
							(end -0.4318 -0.3302)
						)
						(arc
							(start -0.4318 0.3302)
							(mid -0.402042 0.402042)
							(end -0.3302 0.4318)
						)
						(arc
							(start 0.3302 0.4318)
							(mid 0.402042 0.402042)
							(end 0.4318 0.3302)
						)
						(arc
							(start 0.4318 -0.3302)
							(mid 0.402042 -0.402042)
							(end 0.3302 -0.4318)
						)
					)
					(width 0)
					(fill yes)
				)
			)
		)
	)
	(footprint ""
		(layer "F.Cu")
		(at 110.49 -47.371 180)
		(property "Reference" "C363"
			(at 0 0 180)
			(layer "F.SilkS")
			(hide yes)
			(effects
				(font
					(size 1.27 1.27)
				)
			)
		)
		(property "Value" "SC47U16V0MX-GP"
			(at -0.00254 -4.78536 180)
			(unlocked yes)
			(layer "F.Fab")
			(hide yes)
			(effects
				(font
					(size 1.016 1.016)
					(thickness 0.1524)
				)
			)
		)
		(property "Device Type" "C1210H107"
			(at -0.00254 -6.38048 180)
			(unlocked yes)
			(layer "F.Fab")
			(hide yes)
			(effects
				(font
					(size 1.016 1.016)
					(thickness 0.1524)
				)
			)
		)
		(duplicate_pad_numbers_are_jumpers no)
		(fp_line
			(start 1.5748 2.3368)
			(end 1.5748 0.762)
			(stroke
				(width 0.1524)
				(type default)
			)
			(layer "F.SilkS")
		)
		(fp_line
			(start 1.5748 -0.762)
			(end 1.5748 -2.3368)
			(stroke
				(width 0.1524)
				(type default)
			)
			(layer "F.SilkS")
		)
		(fp_line
			(start 1.5748 -2.3368)
			(end -1.5748 -2.3368)
			(stroke
				(width 0.1524)
				(type default)
			)
			(layer "F.SilkS")
		)
		(fp_line
			(start -1.5748 2.3368)
			(end 1.5748 2.3368)
			(stroke
				(width 0.1524)
				(type default)
			)
			(layer "F.SilkS")
		)
		(fp_line
			(start -1.5748 0.762)
			(end -1.5748 2.3368)
			(stroke
				(width 0.1524)
				(type default)
			)
			(layer "F.SilkS")
		)
		(fp_line
			(start -1.5748 -2.3368)
			(end -1.5748 -0.762)
			(stroke
				(width 0.1524)
				(type default)
			)
			(layer "F.SilkS")
		)
		(fp_rect
			(start -1.651 2.413)
			(end 1.651 -2.413)
			(stroke
				(width 0)
				(type default)
			)
			(fill no)
			(layer "F.CrtYd")
		)
		(fp_poly
			(pts
				(xy 1.651 2.413) (xy 1.651 -2.413) (xy -1.651 -2.413) (xy -1.651 2.413)
			)
			(stroke
				(width 0)
				(type default)
			)
			(fill no)
			(layer "F.Fab")
		)
		(pad "1" smd rect
			(at 0 -1.4732 180)
			(size 2.794 1.397)
			(layers "F.Cu" "F.Mask" "F.Paste")
			(net "P12V")
		)
		(pad "2" smd rect
			(at 0 1.4732 180)
			(size 2.794 1.397)
			(layers "F.Cu" "F.Mask" "F.Paste")
			(net "GND")
		)
	)
	(footprint ""
		(layer "F.Cu")
		(at 15.253208 -98.803968)
		(property "Reference" "R353"
			(at 0 0 0)
			(layer "F.SilkS")
			(hide yes)
			(effects
				(font
					(size 1.27 1.27)
				)
			)
		)
		(property "Value" "10KR2F-2-GP"
			(at 0.064008 -3.993896 0)
			(unlocked yes)
			(layer "F.Fab")
			(hide yes)
			(effects
				(font
					(size 1.016 1.016)
					(thickness 0.1524)
				)
			)
		)
		(property "Device Type" "R402H16"
			(at 0.064008 -5.517896 0)
			(unlocked yes)
			(layer "F.Fab")
			(hide yes)
			(effects
				(font
					(size 1.016 1.016)
					(thickness 0.1524)
				)
			)
		)
		(duplicate_pad_numbers_are_jumpers no)
		(fp_line
			(start -0.508 -0.9398)
			(end -0.508 0.9398)
			(stroke
				(width 0.1524)
				(type default)
			)
			(layer "F.SilkS")
		)
		(fp_line
			(start 0.508 -0.9398)
			(end -0.508 -0.9398)
			(stroke
				(width 0.1524)
				(type default)
			)
			(layer "F.SilkS")
		)
		(fp_rect
			(start -0.508 0.9398)
			(end 0.508 -0.9398)
			(stroke
				(width 0)
				(type default)
			)
			(fill no)
			(layer "F.CrtYd")
		)
		(fp_rect
			(start -0.508 0.9398)
			(end 0.508 -0.9398)
			(stroke
				(width 0)
				(type default)
			)
			(fill no)
			(layer "F.Fab")
		)
		(pad "1" smd custom
			(at 0 -0.4445)
			(size 0.1397 0.1397)
			(layers "F.Cu" "F.Mask" "F.Paste")
			(net "P3V3")
			(options
				(clearance outline)
				(anchor circle)
			)
			(primitives
				(gr_poly
					(pts
						(arc
							(start -0.1778 -0.2794)
							(mid -0.249642 -0.249642)
							(end -0.2794 -0.1778)
						)
						(arc
							(start -0.2794 0.1778)
							(mid -0.249642 0.249642)
							(end -0.1778 0.2794)
						)
						(arc
							(start 0.1778 0.2794)
							(mid 0.249642 0.249642)
							(end 0.2794 0.1778)
						)
						(arc
							(start 0.2794 -0.1778)
							(mid 0.249642 -0.249642)
							(end 0.1778 -0.2794)
						)
					)
					(width 0)
					(fill yes)
				)
			)
		)
		(pad "2" smd custom
			(at 0 0.4445)
			(size 0.1397 0.1397)
			(layers "F.Cu" "F.Mask" "F.Paste")
			(net "I2C_C_BUF_READY")
			(options
				(clearance outline)
				(anchor circle)
			)
			(primitives
				(gr_poly
					(pts
						(arc
							(start -0.1778 -0.2794)
							(mid -0.249642 -0.249642)
							(end -0.2794 -0.1778)
						)
						(arc
							(start -0.2794 0.1778)
							(mid -0.249642 0.249642)
							(end -0.1778 0.2794)
						)
						(arc
							(start 0.1778 0.2794)
							(mid 0.249642 0.249642)
							(end 0.2794 0.1778)
						)
						(arc
							(start 0.2794 -0.1778)
							(mid 0.249642 -0.249642)
							(end 0.1778 -0.2794)
						)
					)
					(width 0)
					(fill yes)
				)
			)
		)
	)
	(footprint ""
		(layer "F.Cu")
		(at 155.650692 -103.082344)
		(property "Reference" "PR65"
			(at 0 0 0)
			(layer "F.SilkS")
			(hide yes)
			(effects
				(font
					(size 1.27 1.27)
				)
			)
		)
		(property "Value" "0R3J-0-U-GP"
			(at -0.0254 -2.5146 0)
			(unlocked yes)
			(layer "F.Fab")
			(hide yes)
			(effects
				(font
					(size 1.016 1.016)
					(thickness 0.1524)
				)
			)
		)
		(property "Device Type" "R603H22"
			(at -0.0254 -4.0386 0)
			(unlocked yes)
			(layer "F.Fab")
			(hide yes)
			(effects
				(font
					(size 1.016 1.016)
					(thickness 0.1524)
				)
			)
		)
		(duplicate_pad_numbers_are_jumpers no)
		(fp_line
			(start -0.4826 0)
			(end -0.2032 0)
			(stroke
				(width 0.2032)
				(type default)
			)
			(layer "F.SilkS")
		)
		(fp_line
			(start 0.2032 0)
			(end 0.4826 0)
			(stroke
				(width 0.2032)
				(type default)
			)
			(layer "F.SilkS")
		)
		(fp_rect
			(start -0.5842 1.3335)
			(end 0.5842 -1.3335)
			(stroke
				(width 0)
				(type default)
			)
			(fill no)
			(layer "F.CrtYd")
		)
		(fp_rect
			(start -0.5842 1.3335)
			(end 0.5842 -1.3335)
			(stroke
				(width 0)
				(type default)
			)
			(fill no)
			(layer "F.Fab")
		)
		(pad "1" smd custom
			(at 0 -0.762)
			(size 0.2159 0.2159)
			(layers "F.Cu" "F.Mask" "F.Paste")
			(net "P3V3")
			(options
				(clearance outline)
				(anchor circle)
			)
			(primitives
				(gr_poly
					(pts
						(arc
							(start -0.3302 -0.4318)
							(mid -0.402042 -0.402042)
							(end -0.4318 -0.3302)
						)
						(arc
							(start -0.4318 0.3302)
							(mid -0.402042 0.402042)
							(end -0.3302 0.4318)
						)
						(arc
							(start 0.3302 0.4318)
							(mid 0.402042 0.402042)
							(end 0.4318 0.3302)
						)
						(arc
							(start 0.4318 -0.3302)
							(mid 0.402042 -0.402042)
							(end 0.3302 -0.4318)
						)
					)
					(width 0)
					(fill yes)
				)
			)
		)
		(pad "2" smd custom
			(at 0 0.762)
			(size 0.2159 0.2159)
			(layers "F.Cu" "F.Mask" "F.Paste")
			(net "DETECTOR_C")
			(options
				(clearance outline)
				(anchor circle)
			)
			(primitives
				(gr_poly
					(pts
						(arc
							(start -0.3302 -0.4318)
							(mid -0.402042 -0.402042)
							(end -0.4318 -0.3302)
						)
						(arc
							(start -0.4318 0.3302)
							(mid -0.402042 0.402042)
							(end -0.3302 0.4318)
						)
						(arc
							(start 0.3302 0.4318)
							(mid 0.402042 0.402042)
							(end 0.4318 0.3302)
						)
						(arc
							(start 0.4318 -0.3302)
							(mid 0.402042 -0.402042)
							(end 0.3302 -0.4318)
						)
					)
					(width 0)
					(fill yes)
				)
			)
		)
	)
)
